# S9S_MB_2U (Grand Teton) — schematic netlist excerpt (pin names and nets, part order shuffled) for the footprints in the layout excerpt that follows; sources: Cadence DE-HDL packaged netlist, KiCad conversion of 03242023_DA0F0TMBIJ0_F0T_Motherboard_J_brd_V01_OCP.brd

J105  CONN112_10137002101LF  CONN112_10137002-101LF IO  pkg HSD_F112D8_P2W1-2_RDH  page 136
  A1  = GPU_3V3IO_RSVD4
  A2  = GND
  A3  = GPU_WP_HW_CTRL_ISO
  A4  = GND
  A5  = GPU_3V3IO_RSVD3
  A6  = GND
  A7  = GPU_3V3IO_RSVD1
  A8  = GND
  B1  = GND
  B2  = P5E_CPU0_PE3_RX_DP<6>
  B3  = GND
  B4  = P5E_CPU0_PE3_RX_DP<4>
  B5  = GND
  B6  = P5E_CPU0_PE3_RX_DN<2>
  B7  = GND
  B8  = P5E_CPU0_PE3_RX_DP<0>
  C1  = P5E_CPU0_PE3_RX_DP<7>
  C2  = P5E_CPU0_PE3_RX_DN<6>
  C3  = P5E_CPU0_PE3_RX_DP<5>
  C4  = P5E_CPU0_PE3_RX_DN<4>
  C5  = P5E_CPU0_PE3_RX_DN<3>
  C6  = P5E_CPU0_PE3_RX_DP<2>
  C7  = P5E_CPU0_PE3_RX_DN<1>
  C8  = P5E_CPU0_PE3_RX_DN<0>
  D1  = P5E_CPU0_PE3_RX_DN<7>
  D2  = GND
  D3  = P5E_CPU0_PE3_RX_DN<5>
  D4  = GND
  D5  = P5E_CPU0_PE3_RX_DP<3>
  D6  = GND
  D7  = P5E_CPU0_PE3_RX_DP<1>
  D8  = GND
  E1  = GND
  E2  = P5E_CPU0_PE2_RX_DP<6>
  E3  = GND
  E4  = P5E_CPU0_PE2_RX_DP<4>
  E5  = GND
  E6  = P5E_CPU0_PE2_RX_DP<2>
  E7  = GND
  E8  = P5E_CPU0_PE2_RX_DP<0>
  F1  = P5E_CPU0_PE2_RX_DP<7>
  F2  = P5E_CPU0_PE2_RX_DN<6>
  F3  = P5E_CPU0_PE2_RX_DP<5>
  F4  = P5E_CPU0_PE2_RX_DN<4>
  F5  = P5E_CPU0_PE2_RX_DP<3>
  F6  = P5E_CPU0_PE2_RX_DN<2>
  F7  = P5E_CPU0_PE2_RX_DP<1>
  F8  = P5E_CPU0_PE2_RX_DN<0>
  G1  = P5E_CPU0_PE2_RX_DN<7>
  G2  = GND
  G3  = P5E_CPU0_PE2_RX_DN<5>
  G4  = GND
  G5  = P5E_CPU0_PE2_RX_DN<3>
  G6  = GND
  G7  = P5E_CPU0_PE2_RX_DN<1>
  G8  = GND
  H1  = GND
  H2  = P5E_CPU0_PE3_TX_C_DN<6>
  H3  = GND
  H4  = P5E_CPU0_PE3_TX_C_DN<4>
  H5  = GND
  H6  = P5E_CPU0_PE3_TX_C_DN<2>
  H7  = GND
  H8  = P5E_CPU0_PE3_TX_C_DP<0>
  I1  = P5E_CPU0_PE3_TX_C_DN<7>
  I2  = P5E_CPU0_PE3_TX_C_DP<6>
  I3  = P5E_CPU0_PE3_TX_C_DN<5>
  I4  = P5E_CPU0_PE3_TX_C_DP<4>
  I5  = P5E_CPU0_PE3_TX_C_DN<3>
  I6  = P5E_CPU0_PE3_TX_C_DP<2>
  I7  = P5E_CPU0_PE3_TX_C_DN<1>
  I8  = P5E_CPU0_PE3_TX_C_DN<0>
  J1  = P5E_CPU0_PE3_TX_C_DP<7>
  J2  = GND
  J3  = P5E_CPU0_PE3_TX_C_DP<5>
  J4  = GND
  J5  = P5E_CPU0_PE3_TX_C_DP<3>
  J6  = GND
  J7  = P5E_CPU0_PE3_TX_C_DP<1>
  J8  = GND
  K1  = GND
  K2  = P5E_CPU0_PE2_TX_C_DP<6>
  K3  = GND
  K4  = P5E_CPU0_PE2_TX_C_DP<4>
  K5  = GND
  K6  = P5E_CPU0_PE2_TX_C_DP<2>
  K7  = GND
  K8  = P5E_CPU0_PE2_TX_C_DP<0>
  L1  = P5E_CPU0_PE2_TX_C_DP<7>
  L2  = P5E_CPU0_PE2_TX_C_DN<6>
  L3  = P5E_CPU0_PE2_TX_C_DP<5>
  L4  = P5E_CPU0_PE2_TX_C_DN<4>
  L5  = P5E_CPU0_PE2_TX_C_DP<3>
  L6  = P5E_CPU0_PE2_TX_C_DN<2>
  L7  = P5E_CPU0_PE2_TX_C_DP<1>
  L8  = P5E_CPU0_PE2_TX_C_DN<0>
  M1  = P5E_CPU0_PE2_TX_C_DN<7>
  M2  = GND
  M3  = P5E_CPU0_PE2_TX_C_DN<5>
  M4  = GND
  M5  = P5E_CPU0_PE2_TX_C_DN<3>
  M6  = GND
  M7  = P5E_CPU0_PE2_TX_C_DN<1>
  M8  = GND
  N1  = GND
  N2  = FM_SWB_PWR_EN_R_BUF
  N3  = GND
  N4  = FM_SWB_BIC_READY_N
  N5  = GND
  N6  = RST_SWB_BIC_BUF_N
  N7  = GND
  N8  = RST_BMC_FROM_SWB_N

(kicad_pcb
	(version 20260206)
	(generator "pcbnew")
	(generator_version "10.0")
	(general
		(thickness 1.6)
		(legacy_teardrops no)
	)
	(paper "A4")
	(title_block
		(title "03242023_DA0F0TMBIJ0_F0T_Motherboard_J_brd_V01_OCP.brd")
		(comment 1 "Grand Teton / footprint 1792 of 6105 (J105), pads 32-48 of 48")
	)
	(layers
		(0 "F.Cu" signal "TOP")
		(4 "In1.Cu" signal "GND")
		(6 "In2.Cu" signal "IN1")
		(8 "In3.Cu" signal "GND1")
		(10 "In4.Cu" signal "IN2")
		(12 "In5.Cu" signal "GND2")
		(14 "In6.Cu" signal "IN3")
		(16 "In7.Cu" signal "GND3")
		(18 "In8.Cu" signal "VCC")
		(20 "In9.Cu" signal "VCC1")
		(22 "In10.Cu" signal "GND4")
		(24 "In11.Cu" signal "IN4")
		(26 "In12.Cu" signal "GND5")
		(28 "In13.Cu" signal "IN5")
		(30 "In14.Cu" signal "GND6")
		(32 "In15.Cu" signal "IN6")
		(34 "In16.Cu" signal "GND7")
		(2 "B.Cu" signal "BOTTOM")
		(9 "F.Adhes" user "F.Adhesive")
		(11 "B.Adhes" user "B.Adhesive")
		(13 "F.Paste" user "Package Geometry/Pastemask Top")
		(15 "B.Paste" user "Package Geometry/Pastemask Bottom")
		(5 "F.SilkS" user "Ref Des/Silkscreen Top")
		(7 "B.SilkS" user "Ref Des/Silkscreen Bottom")
		(1 "F.Mask" user "Board Geometry/Soldermask Top")
		(3 "B.Mask" user "Board Geometry/Soldermask Bottom")
		(17 "Dwgs.User" user "User.Drawings")
		(19 "Cmts.User" user "User.Comments")
		(21 "Eco1.User" user "User.Eco1")
		(23 "Eco2.User" user "User.Eco2")
		(25 "Edge.Cuts" user "Board Geometry/Outline")
		(27 "Margin" user)
		(31 "F.CrtYd" user "Package Geometry/Place Bound Top")
		(29 "B.CrtYd" user "Package Geometry/Place Bound Bottom")
		(35 "F.Fab" user "Ref Des/Assembly Top")
		(33 "B.Fab" user "Ref Des/Assembly Bottom")
	)
	(footprint ""
		(layer "F.Cu")
		(at 398.750028 -440.489848)
		(property "Reference" "J105"
			(at -2.99466 23.400512 0)
			(unlocked yes)
			(layer "F.SilkS")
			(effects
				(font
					(size 0.7874 0.5842)
					(thickness 0.1524)
				)
				(justify left)
			)
		)
		(property "Value" ""
			(at 0 0 0)
			(layer "F.Fab")
			(effects
				(font
					(size 1.27 1.27)
				)
			)
		)
		(duplicate_pad_numbers_are_jumpers no)
		(pad "J8" thru_hole circle
			(at 13.999972 10.999978 180)
			(size 0.906272 0.906272)
			(drill 0.499872)
			(layers "*.Cu" "*.Mask")
			(remove_unused_layers no)
			(net "GND")
			(clearance 0.0508)
			(thermal_gap 0.0508)
		)
		(pad "K1" thru_hole circle
			(at 0 11.999976 180)
			(size 0.906272 0.906272)
			(drill 0.499872)
			(layers "*.Cu" "*.Mask")
			(remove_unused_layers no)
			(net "GND")
			(clearance 0.0508)
			(thermal_gap 0.0508)
		)
		(pad "K3" thru_hole circle
			(at 3.999992 11.999976 180)
			(size 0.906272 0.906272)
			(drill 0.499872)
			(layers "*.Cu" "*.Mask")
			(remove_unused_layers no)
			(net "GND")
			(clearance 0.0508)
			(thermal_gap 0.0508)
		)
		(pad "K5" thru_hole circle
			(at 7.999984 11.999976 180)
			(size 0.906272 0.906272)
			(drill 0.499872)
			(layers "*.Cu" "*.Mask")
			(remove_unused_layers no)
			(net "GND")
			(clearance 0.0508)
			(thermal_gap 0.0508)
		)
		(pad "K7" thru_hole circle
			(at 11.999976 11.999976 180)
			(size 0.906272 0.906272)
			(drill 0.499872)
			(layers "*.Cu" "*.Mask")
			(remove_unused_layers no)
			(net "GND")
			(clearance 0.0508)
			(thermal_gap 0.0508)
		)
		(pad "M2" thru_hole circle
			(at 1.999996 14.59992 180)
			(size 0.906272 0.906272)
			(drill 0.499872)
			(layers "*.Cu" "*.Mask")
			(remove_unused_layers no)
			(net "GND")
			(clearance 0.0508)
			(thermal_gap 0.0508)
		)
		(pad "M4" thru_hole circle
			(at 5.999988 14.59992 180)
			(size 0.906272 0.906272)
			(drill 0.499872)
			(layers "*.Cu" "*.Mask")
			(remove_unused_layers no)
			(net "GND")
			(clearance 0.0508)
			(thermal_gap 0.0508)
		)
		(pad "M6" thru_hole circle
			(at 9.99998 14.59992 180)
			(size 0.906272 0.906272)
			(drill 0.499872)
			(layers "*.Cu" "*.Mask")
			(remove_unused_layers no)
			(net "GND")
			(clearance 0.0508)
			(thermal_gap 0.0508)
		)
		(pad "M8" thru_hole circle
			(at 13.999972 14.59992 180)
			(size 0.906272 0.906272)
			(drill 0.499872)
			(layers "*.Cu" "*.Mask")
			(remove_unused_layers no)
			(net "GND")
			(clearance 0.0508)
			(thermal_gap 0.0508)
		)
		(pad "N1" thru_hole circle
			(at 0 15.599918 180)
			(size 0.906272 0.906272)
			(drill 0.499872)
			(layers "*.Cu" "*.Mask")
			(remove_unused_layers no)
			(net "GND")
			(clearance 0.0508)
			(thermal_gap 0.0508)
		)
		(pad "N2" thru_hole circle
			(at 1.999996 15.80007 180)
			(size 0.766318 0.766318)
			(drill 0.359918)
			(layers "*.Cu" "*.Mask")
			(remove_unused_layers no)
			(net "FM_SWB_PWR_EN_R_BUF")
			(clearance 0.0508)
			(thermal_gap 0.0508)
		)
		(pad "N3" thru_hole circle
			(at 3.999992 15.599918 180)
			(size 0.906272 0.906272)
			(drill 0.499872)
			(layers "*.Cu" "*.Mask")
			(remove_unused_layers no)
			(net "GND")
			(clearance 0.0508)
			(thermal_gap 0.0508)
		)
		(pad "N4" thru_hole circle
			(at 5.999988 15.80007 180)
			(size 0.766318 0.766318)
			(drill 0.359918)
			(layers "*.Cu" "*.Mask")
			(remove_unused_layers no)
			(net "FM_SWB_BIC_READY_N")
			(clearance 0.0508)
			(thermal_gap 0.0508)
		)
		(pad "N5" thru_hole circle
			(at 7.999984 15.599918 180)
			(size 0.906272 0.906272)
			(drill 0.499872)
			(layers "*.Cu" "*.Mask")
			(remove_unused_layers no)
			(net "GND")
			(clearance 0.0508)
			(thermal_gap 0.0508)
		)
		(pad "N6" thru_hole circle
			(at 9.99998 15.80007 180)
			(size 0.766318 0.766318)
			(drill 0.359918)
			(layers "*.Cu" "*.Mask")
			(remove_unused_layers no)
			(net "RST_SWB_BIC_BUF_N")
			(clearance 0.0508)
			(thermal_gap 0.0508)
		)
		(pad "N7" thru_hole circle
			(at 11.999976 15.599918 180)
			(size 0.906272 0.906272)
			(drill 0.499872)
			(layers "*.Cu" "*.Mask")
			(remove_unused_layers no)
			(net "GND")
			(clearance 0.0508)
			(thermal_gap 0.0508)
		)
		(pad "N8" thru_hole circle
			(at 13.999972 15.80007 180)
			(size 0.766318 0.766318)
			(drill 0.359918)
			(layers "*.Cu" "*.Mask")
			(remove_unused_layers no)
			(net "RST_BMC_FROM_SWB_N")
			(clearance 0.0508)
			(thermal_gap 0.0508)
		)
	)
)
